(kicad_pcb
	(version 20260206)
	(generator "pcbnew")
	(generator_version "10.0")
	(general
		(thickness 1.6)
		(legacy_teardrops no)
	)
	(paper "A4")
	(title_block
		(title "01162023_DA0F0TEBIF0_F0T_Expander_BD_F_brd_V02_OCP.brd")
		(comment 1 "Grand Teton / footprints 2408-2414 of 9728")
	)
	(layers
		(0 "F.Cu" signal "TOP")
		(4 "In1.Cu" signal "GND")
		(6 "In2.Cu" signal "VCC")
		(8 "In3.Cu" signal "VCC1")
		(10 "In4.Cu" signal "GND1")
		(12 "In5.Cu" signal "IN1")
		(14 "In6.Cu" signal "GND2")
		(16 "In7.Cu" signal "IN2")
		(18 "In8.Cu" signal "GND3")
		(20 "In9.Cu" signal "IN3")
		(22 "In10.Cu" signal "GND4")
		(24 "In11.Cu" signal "IN4")
		(26 "In12.Cu" signal "GND5")
		(28 "In13.Cu" signal "IN5")
		(30 "In14.Cu" signal "GND6")
		(32 "In15.Cu" signal "IN6")
		(34 "In16.Cu" signal "GND7")
		(2 "B.Cu" signal "BOTTOM")
		(9 "F.Adhes" user "F.Adhesive")
		(11 "B.Adhes" user "B.Adhesive")
		(13 "F.Paste" user "Package Geometry/Pastemask Top")
		(15 "B.Paste" user "Package Geometry/Pastemask Bottom")
		(5 "F.SilkS" user "Ref Des/Silkscreen Top")
		(7 "B.SilkS" user "Ref Des/Silkscreen Bottom")
		(1 "F.Mask" user "Board Geometry/Soldermask Top")
		(3 "B.Mask" user "Board Geometry/Soldermask Bottom")
		(17 "Dwgs.User" user "User.Drawings")
		(19 "Cmts.User" user "User.Comments")
		(21 "Eco1.User" user "User.Eco1")
		(23 "Eco2.User" user "User.Eco2")
		(25 "Edge.Cuts" user "Board Geometry/Outline")
		(27 "Margin" user)
		(31 "F.CrtYd" user "Package Geometry/Place Bound Top")
		(29 "B.CrtYd" user "Package Geometry/Place Bound Bottom")
		(35 "F.Fab" user "Ref Des/Assembly Top")
		(33 "B.Fab" user "Ref Des/Assembly Bottom")
	)
	(footprint ""
		(layer "F.Cu")
		(at 135.882888 -225.49993 180)
		(property "Reference" "JPEX1"
			(at -8.892286 -8.467852 0)
			(unlocked yes)
			(layer "F.SilkS")
			(effects
				(font
					(size 0.7874 0.5842)
					(thickness 0.1524)
				)
				(justify left)
			)
		)
		(property "Value" ""
			(at 0 0 180)
			(layer "F.Fab")
			(effects
				(font
					(size 1.27 1.27)
				)
			)
		)
		(duplicate_pad_numbers_are_jumpers no)
		(fp_line
			(start 12.46505 7.649972)
			(end -12.46505 7.649972)
			(stroke
				(width 0.1524)
				(type default)
			)
			(layer "F.SilkS")
		)
		(fp_line
			(start 12.46505 -7.649972)
			(end 12.46505 7.649972)
			(stroke
				(width 0.1524)
				(type default)
			)
			(layer "F.SilkS")
		)
		(fp_line
			(start 6.945122 7.649972)
			(end -6.945122 7.649972)
			(stroke
				(width 0.1524)
				(type default)
			)
			(layer "F.SilkS")
		)
		(fp_line
			(start 6.945122 -7.649972)
			(end 6.945122 7.649972)
			(stroke
				(width 0.1524)
				(type default)
			)
			(layer "F.SilkS")
		)
		(fp_line
			(start 6.945122 -7.649972)
			(end 0 -7.649972)
			(stroke
				(width 0.1524)
				(type default)
			)
			(layer "F.SilkS")
		)
		(fp_line
			(start 0 -7.649972)
			(end 12.46505 -7.649972)
			(stroke
				(width 0.1524)
				(type default)
			)
			(layer "F.SilkS")
		)
		(fp_line
			(start -6.945122 -7.649972)
			(end 0 -7.649972)
			(stroke
				(width 0.1524)
				(type default)
			)
			(layer "F.SilkS")
		)
		(fp_line
			(start -6.945122 -7.649972)
			(end -6.945122 7.649972)
			(stroke
				(width 0.1524)
				(type default)
			)
			(layer "F.SilkS")
		)
		(fp_line
			(start -12.46505 7.649972)
			(end -12.46505 -7.649972)
			(stroke
				(width 0.1524)
				(type default)
			)
			(layer "F.SilkS")
		)
		(fp_line
			(start -12.46505 -7.649972)
			(end 0 -7.649972)
			(stroke
				(width 0.1524)
				(type default)
			)
			(layer "F.SilkS")
		)
		(fp_poly
			(pts
				(xy -7.112 -4.445) (xy -8.128 -4.953) (xy -8.128 -3.937)
			)
			(stroke
				(width 0)
				(type default)
			)
			(fill yes)
			(layer "F.SilkS")
		)
		(fp_line
			(start 6.945122 7.649972)
			(end -6.945122 7.649972)
			(stroke
				(width 0.1)
				(type default)
			)
			(layer "F.Fab")
		)
		(fp_line
			(start 6.945122 -7.649972)
			(end 6.945122 7.649972)
			(stroke
				(width 0.1)
				(type default)
			)
			(layer "F.Fab")
		)
		(fp_line
			(start -6.945122 7.649972)
			(end -6.945122 -7.649972)
			(stroke
				(width 0.1)
				(type default)
			)
			(layer "F.Fab")
		)
		(fp_line
			(start -6.945122 -7.649972)
			(end 6.945122 -7.649972)
			(stroke
				(width 0.1)
				(type default)
			)
			(layer "F.Fab")
		)
		(fp_poly
			(pts
				(xy -7.112 -4.445) (xy -8.128 -4.953) (xy -8.128 -3.937)
			)
			(stroke
				(width 0)
				(type default)
			)
			(fill yes)
			(layer "F.Fab")
		)
		(fp_text user "9"
			(at 7.51713 4.1656 90)
			(unlocked yes)
			(layer "F.SilkS")
			(effects
				(font
					(size 0.7874 0.5842)
					(thickness 0.1524)
				)
				(justify left)
			)
		)
		(fp_text user "16"
			(at 7.49173 -5.2324 90)
			(unlocked yes)
			(layer "F.SilkS")
			(effects
				(font
					(size 0.7874 0.5842)
					(thickness 0.1524)
				)
				(justify left)
			)
		)
		(fp_text user "8"
			(at -7.77367 4.2164 90)
			(unlocked yes)
			(layer "F.SilkS")
			(effects
				(font
					(size 0.7874 0.5842)
					(thickness 0.1524)
				)
				(justify left)
			)
		)
		(fp_text user "9"
			(at 7.51713 4.1656 90)
			(unlocked yes)
			(layer "F.Fab")
			(effects
				(font
					(size 0.7874 0.5842)
					(thickness 0.1524)
				)
				(justify left)
			)
		)
		(fp_text user "16"
			(at 7.49173 -5.2324 90)
			(unlocked yes)
			(layer "F.Fab")
			(effects
				(font
					(size 0.7874 0.5842)
					(thickness 0.1524)
				)
				(justify left)
			)
		)
		(fp_text user "8"
			(at -7.77367 4.2164 90)
			(unlocked yes)
			(layer "F.Fab")
			(effects
				(font
					(size 0.7874 0.5842)
					(thickness 0.1524)
				)
				(justify left)
			)
		)
		(pad "1" smd rect
			(at -4.800092 -4.445 90)
			(size 0.508 1.524)
			(layers "F.Cu" "F.Mask" "F.Paste")
			(net "SPI_PEX1_SDIO3_R1")
		)
		(pad "2" smd rect
			(at -4.800092 -3.175 90)
			(size 0.508 1.524)
			(layers "F.Cu" "F.Mask" "F.Paste")
			(net "P1V8_PEX")
		)
		(pad "3" smd rect
			(at -4.800092 -1.905 90)
			(size 0.508 1.524)
			(layers "F.Cu" "F.Mask" "F.Paste")
			(net "SPI_PEX1_RST_R_N")
		)
		(pad "4" smd rect
			(at -4.800092 -0.635 90)
			(size 0.508 1.524)
			(layers "F.Cu" "F.Mask" "F.Paste")
			(net "Net_2691")
		)
		(pad "5" smd rect
			(at -4.800092 0.635 90)
			(size 0.508 1.524)
			(layers "F.Cu" "F.Mask" "F.Paste")
			(net "Net_2690")
		)
		(pad "6" smd rect
			(at -4.800092 1.905 90)
			(size 0.508 1.524)
			(layers "F.Cu" "F.Mask" "F.Paste")
			(net "Net_2689")
		)
		(pad "7" smd rect
			(at -4.800092 3.175 90)
			(size 0.508 1.524)
			(layers "F.Cu" "F.Mask" "F.Paste")
			(net "SPI_PEX1_CS_MUX_R_N")
		)
		(pad "8" smd rect
			(at -4.800092 4.445 90)
			(size 0.508 1.524)
			(layers "F.Cu" "F.Mask" "F.Paste")
			(net "SPI_PEX1_SDIO1_MUX_R")
		)
		(pad "9" smd rect
			(at 4.800092 4.445 90)
			(size 0.508 1.524)
			(layers "F.Cu" "F.Mask" "F.Paste")
			(net "SPI_PEX1_SDIO2_R1")
		)
		(pad "10" smd rect
			(at 4.800092 3.175 90)
			(size 0.508 1.524)
			(layers "F.Cu" "F.Mask" "F.Paste")
			(net "GND")
		)
		(pad "11" smd rect
			(at 4.800092 1.905 90)
			(size 0.508 1.524)
			(layers "F.Cu" "F.Mask" "F.Paste")
			(net "Net_2692")
		)
		(pad "12" smd rect
			(at 4.800092 0.635 90)
			(size 0.508 1.524)
			(layers "F.Cu" "F.Mask" "F.Paste")
			(net "Net_2693")
		)
		(pad "13" smd rect
			(at 4.800092 -0.635 90)
			(size 0.508 1.524)
			(layers "F.Cu" "F.Mask" "F.Paste")
			(net "Net_2694")
		)
		(pad "14" smd rect
			(at 4.800092 -1.905 90)
			(size 0.508 1.524)
			(layers "F.Cu" "F.Mask" "F.Paste")
			(net "Net_2695")
		)
		(pad "15" smd rect
			(at 4.800092 -3.175 90)
			(size 0.508 1.524)
			(layers "F.Cu" "F.Mask" "F.Paste")
			(net "SPI_PEX1_SDIO0_MUX_R")
		)
		(pad "16" smd rect
			(at 4.800092 -4.445 90)
			(size 0.508 1.524)
			(layers "F.Cu" "F.Mask" "F.Paste")
			(net "SPI_PEX1_CLK_MUX_R")
		)
	)
	(footprint ""
		(layer "F.Cu")
		(at 384.938524 -134.008876)
		(property "Reference" "C668"
			(at 0 0 0)
			(layer "F.SilkS")
			(hide yes)
			(effects
				(font
					(size 1.27 1.27)
				)
			)
		)
		(property "Value" ""
			(at 0 0 0)
			(layer "F.Fab")
			(effects
				(font
					(size 1.27 1.27)
				)
			)
		)
		(duplicate_pad_numbers_are_jumpers no)
		(fp_line
			(start -0.299974 -0.150114)
			(end 0.299974 -0.150114)
			(stroke
				(width 0.1)
				(type default)
			)
			(layer "F.Fab")
		)
		(fp_line
			(start -0.299974 0.150114)
			(end -0.299974 -0.150114)
			(stroke
				(width 0.1)
				(type default)
			)
			(layer "F.Fab")
		)
		(fp_line
			(start 0.299974 -0.150114)
			(end 0.299974 0.150114)
			(stroke
				(width 0.1)
				(type default)
			)
			(layer "F.Fab")
		)
		(fp_line
			(start 0.299974 0.150114)
			(end -0.299974 0.150114)
			(stroke
				(width 0.1)
				(type default)
			)
			(layer "F.Fab")
		)
		(pad "1" smd rect
			(at -0.2667 0)
			(size 0.3048 0.381)
			(layers "F.Cu" "F.Mask" "F.Paste")
			(net "P5E_PEX3_STN1_TX_DP<30>")
		)
		(pad "2" smd rect
			(at 0.2667 0)
			(size 0.3048 0.381)
			(layers "F.Cu" "F.Mask" "F.Paste")
			(net "P5E_PEX3_STN1_TX_C_DP<30>")
		)
	)
	(footprint ""
		(layer "F.Cu")
		(at 183.923432 -350.098614 90)
		(property "Reference" "C380"
			(at 0 0 90)
			(layer "F.SilkS")
			(hide yes)
			(effects
				(font
					(size 1.27 1.27)
				)
			)
		)
		(property "Value" ""
			(at 0 0 90)
			(layer "F.Fab")
			(effects
				(font
					(size 1.27 1.27)
				)
			)
		)
		(duplicate_pad_numbers_are_jumpers no)
		(fp_line
			(start 0.299974 -0.150114)
			(end 0.299974 0.150114)
			(stroke
				(width 0.1)
				(type default)
			)
			(layer "F.Fab")
		)
		(fp_line
			(start -0.299974 -0.150114)
			(end 0.299974 -0.150114)
			(stroke
				(width 0.1)
				(type default)
			)
			(layer "F.Fab")
		)
		(fp_line
			(start 0.299974 0.150114)
			(end -0.299974 0.150114)
			(stroke
				(width 0.1)
				(type default)
			)
			(layer "F.Fab")
		)
		(fp_line
			(start -0.299974 0.150114)
			(end -0.299974 -0.150114)
			(stroke
				(width 0.1)
				(type default)
			)
			(layer "F.Fab")
		)
		(pad "1" smd rect
			(at -0.2667 0 90)
			(size 0.3048 0.381)
			(layers "F.Cu" "F.Mask" "F.Paste")
			(net "P5E_PEX1_STN7_TX_DP<123>")
		)
		(pad "2" smd rect
			(at 0.2667 0 90)
			(size 0.3048 0.381)
			(layers "F.Cu" "F.Mask" "F.Paste")
			(net "P5E_PEX1_STN7_TX_C_DP<123>")
		)
	)
	(footprint ""
		(layer "F.Cu")
		(at 352.920554 -81.501234)
		(property "Reference" "R1629"
			(at 0 0 0)
			(layer "F.SilkS")
			(hide yes)
			(effects
				(font
					(size 1.27 1.27)
				)
			)
		)
		(property "Value" ""
			(at 0 0 0)
			(layer "F.Fab")
			(effects
				(font
					(size 1.27 1.27)
				)
			)
		)
		(duplicate_pad_numbers_are_jumpers no)
		(fp_line
			(start -0.7874 -0.4064)
			(end 0.7874 -0.4064)
			(stroke
				(width 0.1524)
				(type default)
			)
			(layer "F.SilkS")
		)
		(fp_line
			(start -0.7874 0.4064)
			(end -0.7874 -0.4064)
			(stroke
				(width 0.1524)
				(type default)
			)
			(layer "F.SilkS")
		)
		(fp_line
			(start 0.7874 -0.4064)
			(end 0.7874 0.4064)
			(stroke
				(width 0.1524)
				(type default)
			)
			(layer "F.SilkS")
		)
		(fp_line
			(start 0.7874 0.4064)
			(end -0.7874 0.4064)
			(stroke
				(width 0.1524)
				(type default)
			)
			(layer "F.SilkS")
		)
		(fp_line
			(start -0.67945 -0.305054)
			(end -0.12065 -0.305054)
			(stroke
				(width 0.1)
				(type default)
			)
			(layer "F.Fab")
		)
		(fp_line
			(start -0.67945 0.3048)
			(end -0.67945 -0.305054)
			(stroke
				(width 0.1)
				(type default)
			)
			(layer "F.Fab")
		)
		(fp_line
			(start -0.12065 -0.305054)
			(end -0.12065 -0.2794)
			(stroke
				(width 0.1)
				(type default)
			)
			(layer "F.Fab")
		)
		(fp_line
			(start -0.12065 -0.2794)
			(end 0.12065 -0.2794)
			(stroke
				(width 0.1)
				(type default)
			)
			(layer "F.Fab")
		)
		(fp_line
			(start -0.12065 0.2794)
			(end -0.12065 0.3048)
			(stroke
				(width 0.1)
				(type default)
			)
			(layer "F.Fab")
		)
		(fp_line
			(start -0.12065 0.3048)
			(end -0.67945 0.3048)
			(stroke
				(width 0.1)
				(type default)
			)
			(layer "F.Fab")
		)
		(fp_line
			(start 0.120396 0.2794)
			(end -0.12065 0.2794)
			(stroke
				(width 0.1)
				(type default)
			)
			(layer "F.Fab")
		)
		(fp_line
			(start 0.120396 0.3048)
			(end 0.120396 0.2794)
			(stroke
				(width 0.1)
				(type default)
			)
			(layer "F.Fab")
		)
		(fp_line
			(start 0.12065 -0.3048)
			(end 0.67945 -0.3048)
			(stroke
				(width 0.1)
				(type default)
			)
			(layer "F.Fab")
		)
		(fp_line
			(start 0.12065 -0.2794)
			(end 0.12065 -0.3048)
			(stroke
				(width 0.1)
				(type default)
			)
			(layer "F.Fab")
		)
		(fp_line
			(start 0.67945 -0.3048)
			(end 0.67945 0.3048)
			(stroke
				(width 0.1)
				(type default)
			)
			(layer "F.Fab")
		)
		(fp_line
			(start 0.67945 0.3048)
			(end 0.120396 0.3048)
			(stroke
				(width 0.1)
				(type default)
			)
			(layer "F.Fab")
		)
		(pad "1" smd circle
			(at -0.40005 0)
			(size 0 0)
			(layers "F.Cu" "F.Mask" "F.Paste")
			(net "SMB_BIC_I2C9_MUX1_SSD11_R_SCL")
		)
		(pad "2" smd circle
			(at 0.40005 0)
			(size 0 0)
			(layers "F.Cu" "F.Mask" "F.Paste")
			(net "SMB_BIC_I2C9_MUX1_SSD11_SCL")
		)
	)
	(footprint ""
		(layer "F.Cu")
		(at 184.088024 -45.704252 90)
		(property "Reference" "R573"
			(at 0 0 90)
			(layer "F.SilkS")
			(hide yes)
			(effects
				(font
					(size 1.27 1.27)
				)
			)
		)
		(property "Value" ""
			(at 0 0 90)
			(layer "F.Fab")
			(effects
				(font
					(size 1.27 1.27)
				)
			)
		)
		(duplicate_pad_numbers_are_jumpers no)
		(fp_line
			(start 3.937508 -1.8796)
			(end -3.937508 -1.8796)
			(stroke
				(width 0.1524)
				(type default)
			)
			(layer "F.SilkS")
		)
		(fp_line
			(start -3.937508 -1.8796)
			(end -3.937508 1.8796)
			(stroke
				(width 0.1524)
				(type default)
			)
			(layer "F.SilkS")
		)
		(fp_line
			(start 3.937508 1.8796)
			(end 3.937508 -1.8796)
			(stroke
				(width 0.1524)
				(type default)
			)
			(layer "F.SilkS")
		)
		(fp_line
			(start -3.937508 1.8796)
			(end 3.937508 1.8796)
			(stroke
				(width 0.1524)
				(type default)
			)
			(layer "F.SilkS")
		)
		(fp_line
			(start 3.275076 -1.674876)
			(end -3.275076 -1.674876)
			(stroke
				(width 0.1)
				(type default)
			)
			(layer "F.Fab")
		)
		(fp_line
			(start -3.275076 -1.674876)
			(end -3.275076 1.674876)
			(stroke
				(width 0.1)
				(type default)
			)
			(layer "F.Fab")
		)
		(fp_line
			(start 3.275076 1.674876)
			(end 3.275076 -1.674876)
			(stroke
				(width 0.1)
				(type default)
			)
			(layer "F.Fab")
		)
		(fp_line
			(start -3.275076 1.674876)
			(end 3.275076 1.674876)
			(stroke
				(width 0.1)
				(type default)
			)
			(layer "F.Fab")
		)
		(pad "1" smd rect
			(at -2.350008 0 90)
			(size 2.921 3.5052)
			(layers "F.Cu" "F.Mask" "F.Paste")
			(net "P12V_SSD6")
		)
		(pad "2" smd rect
			(at 2.350008 0 90)
			(size 2.921 3.5052)
			(layers "F.Cu" "F.Mask" "F.Paste")
			(net "P12V_SSD6_R")
		)
	)
	(footprint ""
		(layer "F.Cu")
		(at 338.074 -153.67 180)
		(property "Reference" "R4818"
			(at 0 0 180)
			(layer "F.SilkS")
			(hide yes)
			(effects
				(font
					(size 1.27 1.27)
				)
			)
		)
		(property "Value" ""
			(at 0 0 180)
			(layer "F.Fab")
			(effects
				(font
					(size 1.27 1.27)
				)
			)
		)
		(duplicate_pad_numbers_are_jumpers no)
		(fp_line
			(start 0.7874 0.4064)
			(end -0.7874 0.4064)
			(stroke
				(width 0.1524)
				(type default)
			)
			(layer "F.SilkS")
		)
		(fp_line
			(start 0.7874 -0.4064)
			(end 0.7874 0.4064)
			(stroke
				(width 0.1524)
				(type default)
			)
			(layer "F.SilkS")
		)
		(fp_line
			(start -0.7874 0.4064)
			(end -0.7874 -0.4064)
			(stroke
				(width 0.1524)
				(type default)
			)
			(layer "F.SilkS")
		)
		(fp_line
			(start -0.7874 -0.4064)
			(end 0.7874 -0.4064)
			(stroke
				(width 0.1524)
				(type default)
			)
			(layer "F.SilkS")
		)
		(fp_line
			(start 0.67945 0.3048)
			(end 0.120396 0.3048)
			(stroke
				(width 0.1)
				(type default)
			)
			(layer "F.Fab")
		)
		(fp_line
			(start 0.67945 -0.3048)
			(end 0.67945 0.3048)
			(stroke
				(width 0.1)
				(type default)
			)
			(layer "F.Fab")
		)
		(fp_line
			(start 0.12065 -0.2794)
			(end 0.12065 -0.3048)
			(stroke
				(width 0.1)
				(type default)
			)
			(layer "F.Fab")
		)
		(fp_line
			(start 0.12065 -0.3048)
			(end 0.67945 -0.3048)
			(stroke
				(width 0.1)
				(type default)
			)
			(layer "F.Fab")
		)
		(fp_line
			(start 0.120396 0.3048)
			(end 0.120396 0.2794)
			(stroke
				(width 0.1)
				(type default)
			)
			(layer "F.Fab")
		)
		(fp_line
			(start 0.120396 0.2794)
			(end -0.12065 0.2794)
			(stroke
				(width 0.1)
				(type default)
			)
			(layer "F.Fab")
		)
		(fp_line
			(start -0.12065 0.3048)
			(end -0.67945 0.3048)
			(stroke
				(width 0.1)
				(type default)
			)
			(layer "F.Fab")
		)
		(fp_line
			(start -0.12065 0.2794)
			(end -0.12065 0.3048)
			(stroke
				(width 0.1)
				(type default)
			)
			(layer "F.Fab")
		)
		(fp_line
			(start -0.12065 -0.2794)
			(end 0.12065 -0.2794)
			(stroke
				(width 0.1)
				(type default)
			)
			(layer "F.Fab")
		)
		(fp_line
			(start -0.12065 -0.305054)
			(end -0.12065 -0.2794)
			(stroke
				(width 0.1)
				(type default)
			)
			(layer "F.Fab")
		)
		(fp_line
			(start -0.67945 0.3048)
			(end -0.67945 -0.305054)
			(stroke
				(width 0.1)
				(type default)
			)
			(layer "F.Fab")
		)
		(fp_line
			(start -0.67945 -0.305054)
			(end -0.12065 -0.305054)
			(stroke
				(width 0.1)
				(type default)
			)
			(layer "F.Fab")
		)
		(pad "1" smd circle
			(at -0.40005 0 180)
			(size 0 0)
			(layers "F.Cu" "F.Mask" "F.Paste")
			(net "RST_PEX_SSD13_PERST_N")
		)
		(pad "2" smd circle
			(at 0.40005 0 180)
			(size 0 0)
			(layers "F.Cu" "F.Mask" "F.Paste")
			(net "RST_PEX_SSD13_PERST_R_N")
		)
	)
	(footprint ""
		(layer "F.Cu")
		(at 255.935226 -239.095788 -90)
		(property "Reference" "C4425"
			(at 0 0 270)
			(layer "F.SilkS")
			(hide yes)
			(effects
				(font
					(size 1.27 1.27)
				)
			)
		)
		(property "Value" ""
			(at 0 0 270)
			(layer "F.Fab")
			(effects
				(font
					(size 1.27 1.27)
				)
			)
		)
		(duplicate_pad_numbers_are_jumpers no)
		(fp_line
			(start -1.524 0.762)
			(end -1.524 -0.762)
			(stroke
				(width 0.1524)
				(type default)
			)
			(layer "F.SilkS")
		)
		(fp_line
			(start 1.524 0.762)
			(end -1.524 0.762)
			(stroke
				(width 0.1524)
				(type default)
			)
			(layer "F.SilkS")
		)
		(fp_line
			(start -1.524 -0.762)
			(end 1.524 -0.762)
			(stroke
				(width 0.1524)
				(type default)
			)
			(layer "F.SilkS")
		)
		(fp_line
			(start 1.524 -0.762)
			(end 1.524 0.762)
			(stroke
				(width 0.1524)
				(type default)
			)
			(layer "F.SilkS")
		)
		(fp_line
			(start -1.1049 0.724916)
			(end 1.1049 0.724916)
			(stroke
				(width 0.1)
				(type default)
			)
			(layer "F.Fab")
		)
		(fp_line
			(start 1.1049 0.724916)
			(end 1.1049 -0.724916)
			(stroke
				(width 0.1)
				(type default)
			)
			(layer "F.Fab")
		)
		(fp_line
			(start -1.1049 -0.724916)
			(end -1.1049 0.724916)
			(stroke
				(width 0.1)
				(type default)
			)
			(layer "F.Fab")
		)
		(fp_line
			(start 1.1049 -0.724916)
			(end -1.1049 -0.724916)
			(stroke
				(width 0.1)
				(type default)
			)
			(layer "F.Fab")
		)
		(pad "1" smd rect
			(at -0.889 0 90)
			(size 1.016 1.27)
			(layers "F.Cu" "F.Mask" "F.Paste")
			(net "P3V3_AUX")
		)
		(pad "2" smd rect
			(at 0.889 0 90)
			(size 1.016 1.27)
			(layers "F.Cu" "F.Mask" "F.Paste")
			(net "GND")
		)
	)
)
